# T6G (Grand Teton) — schematic netlist excerpt (pin names and nets, part order shuffled) for the footprints in the layout excerpt that follows; sources: Cadence DE-HDL packaged netlist, KiCad conversion of 04192023_DAF0TMB3IC0_F0TG_MB_C_brd_V02_OCP.brd

R2213  Q_RES  2.2K 5% EMPTY  pkg 0402LF  page 151 : A = SMB_HOST_CLK_3V3AUX_SDA ; B = P3V3_AUX
R571  Q_RES  10M 1% CHIP  pkg 0402LF  page 55 : A = XTAL_CPU1_X48M_X1 ; B = XTAL_CPU1_X48M_X2_R

(kicad_pcb
	(version 20260206)
	(generator "pcbnew")
	(generator_version "10.0")
	(general
		(thickness 1.6)
		(legacy_teardrops no)
	)
	(paper "A4")
	(title_block
		(title "04192023_DAF0TMB3IC0_F0TG_MB_C_brd_V02_OCP.brd")
		(comment 1 "Grand Teton / footprints 6665-6666 of 8354")
	)
	(layers
		(0 "F.Cu" signal "TOP")
		(4 "In1.Cu" signal "GND")
		(6 "In2.Cu" signal "IN1")
		(8 "In3.Cu" signal "GND1")
		(10 "In4.Cu" signal "IN2")
		(12 "In5.Cu" signal "GND2")
		(14 "In6.Cu" signal "IN3")
		(16 "In7.Cu" signal "GND3")
		(18 "In8.Cu" signal "VCC")
		(20 "In9.Cu" signal "VCC1")
		(22 "In10.Cu" signal "GND4")
		(24 "In11.Cu" signal "IN4")
		(26 "In12.Cu" signal "GND5")
		(28 "In13.Cu" signal "IN5")
		(30 "In14.Cu" signal "GND6")
		(32 "In15.Cu" signal "IN6")
		(34 "In16.Cu" signal "GND7")
		(2 "B.Cu" signal "BOTTOM")
		(9 "F.Adhes" user "F.Adhesive")
		(11 "B.Adhes" user "B.Adhesive")
		(13 "F.Paste" user "Package Geometry/Pastemask Top")
		(15 "B.Paste" user "Package Geometry/Pastemask Bottom")
		(5 "F.SilkS" user "Ref Des/Silkscreen Top")
		(7 "B.SilkS" user "Ref Des/Silkscreen Bottom")
		(1 "F.Mask" user "Board Geometry/Soldermask Top")
		(3 "B.Mask" user "Board Geometry/Soldermask Bottom")
		(17 "Dwgs.User" user "User.Drawings")
		(19 "Cmts.User" user "User.Comments")
		(21 "Eco1.User" user "User.Eco1")
		(23 "Eco2.User" user "User.Eco2")
		(25 "Edge.Cuts" user "Board Geometry/Outline")
		(27 "Margin" user)
		(31 "F.CrtYd" user "Package Geometry/Place Bound Top")
		(29 "B.CrtYd" user "Package Geometry/Place Bound Bottom")
		(35 "F.Fab" user "Ref Des/Assembly Top")
		(33 "B.Fab" user "Ref Des/Assembly Bottom")
	)
	(footprint ""
		(layer "B.Cu")
		(at 148.122386 -313.45505 180)
		(property "Reference" "R571"
			(at 0 0 0)
			(layer "B.SilkS")
			(hide yes)
			(effects
				(font
					(size 1.27 1.27)
				)
				(justify mirror)
			)
		)
		(property "Value" ""
			(at 0 0 0)
			(layer "B.Fab")
			(effects
				(font
					(size 1.27 1.27)
				)
				(justify mirror)
			)
		)
		(duplicate_pad_numbers_are_jumpers no)
		(fp_line
			(start 0.7874 0.4064)
			(end 0.7874 -0.4064)
			(stroke
				(width 0.1524)
				(type default)
			)
			(layer "B.SilkS")
		)
		(fp_line
			(start 0.7874 -0.4064)
			(end -0.7874 -0.4064)
			(stroke
				(width 0.1524)
				(type default)
			)
			(layer "B.SilkS")
		)
		(fp_line
			(start -0.7874 0.4064)
			(end 0.7874 0.4064)
			(stroke
				(width 0.1524)
				(type default)
			)
			(layer "B.SilkS")
		)
		(fp_line
			(start -0.7874 -0.4064)
			(end -0.7874 0.4064)
			(stroke
				(width 0.1524)
				(type default)
			)
			(layer "B.SilkS")
		)
		(fp_line
			(start 0.67945 0.3048)
			(end 0.67945 -0.305054)
			(stroke
				(width 0.1)
				(type default)
			)
			(layer "B.Fab")
		)
		(fp_line
			(start 0.67945 -0.305054)
			(end 0.12065 -0.305054)
			(stroke
				(width 0.1)
				(type default)
			)
			(layer "B.Fab")
		)
		(fp_line
			(start 0.12065 0.3048)
			(end 0.67945 0.3048)
			(stroke
				(width 0.1)
				(type default)
			)
			(layer "B.Fab")
		)
		(fp_line
			(start 0.12065 0.2794)
			(end 0.12065 0.3048)
			(stroke
				(width 0.1)
				(type default)
			)
			(layer "B.Fab")
		)
		(fp_line
			(start 0.12065 -0.2794)
			(end -0.12065 -0.2794)
			(stroke
				(width 0.1)
				(type default)
			)
			(layer "B.Fab")
		)
		(fp_line
			(start 0.12065 -0.305054)
			(end 0.12065 -0.2794)
			(stroke
				(width 0.1)
				(type default)
			)
			(layer "B.Fab")
		)
		(fp_line
			(start -0.120396 0.3048)
			(end -0.120396 0.2794)
			(stroke
				(width 0.1)
				(type default)
			)
			(layer "B.Fab")
		)
		(fp_line
			(start -0.120396 0.2794)
			(end 0.12065 0.2794)
			(stroke
				(width 0.1)
				(type default)
			)
			(layer "B.Fab")
		)
		(fp_line
			(start -0.12065 -0.2794)
			(end -0.12065 -0.3048)
			(stroke
				(width 0.1)
				(type default)
			)
			(layer "B.Fab")
		)
		(fp_line
			(start -0.12065 -0.3048)
			(end -0.67945 -0.3048)
			(stroke
				(width 0.1)
				(type default)
			)
			(layer "B.Fab")
		)
		(fp_line
			(start -0.67945 0.3048)
			(end -0.120396 0.3048)
			(stroke
				(width 0.1)
				(type default)
			)
			(layer "B.Fab")
		)
		(fp_line
			(start -0.67945 -0.3048)
			(end -0.67945 0.3048)
			(stroke
				(width 0.1)
				(type default)
			)
			(layer "B.Fab")
		)
		(pad "1" smd circle
			(at 0.40005 0)
			(size 0 0)
			(layers "B.Cu" "B.Mask" "B.Paste")
			(net "XTAL_CPU1_X48M_X1")
		)
		(pad "2" smd circle
			(at -0.40005 0)
			(size 0 0)
			(layers "B.Cu" "B.Mask" "B.Paste")
			(net "XTAL_CPU1_X48M_X2_R")
		)
	)
	(footprint ""
		(layer "B.Cu")
		(at 149.718776 -17.693894 -90)
		(property "Reference" "R2213"
			(at 0 0 90)
			(layer "B.SilkS")
			(hide yes)
			(effects
				(font
					(size 1.27 1.27)
				)
				(justify mirror)
			)
		)
		(property "Value" ""
			(at 0 0 90)
			(layer "B.Fab")
			(effects
				(font
					(size 1.27 1.27)
				)
				(justify mirror)
			)
		)
		(duplicate_pad_numbers_are_jumpers no)
		(fp_line
			(start -0.7874 0.4064)
			(end 0.7874 0.4064)
			(stroke
				(width 0.1524)
				(type default)
			)
			(layer "B.SilkS")
		)
		(fp_line
			(start 0.7874 0.4064)
			(end 0.7874 -0.4064)
			(stroke
				(width 0.1524)
				(type default)
			)
			(layer "B.SilkS")
		)
		(fp_line
			(start -0.7874 -0.4064)
			(end -0.7874 0.4064)
			(stroke
				(width 0.1524)
				(type default)
			)
			(layer "B.SilkS")
		)
		(fp_line
			(start 0.7874 -0.4064)
			(end -0.7874 -0.4064)
			(stroke
				(width 0.1524)
				(type default)
			)
			(layer "B.SilkS")
		)
		(fp_line
			(start -0.67945 0.3048)
			(end -0.120396 0.3048)
			(stroke
				(width 0.1)
				(type default)
			)
			(layer "B.Fab")
		)
		(fp_line
			(start -0.120396 0.3048)
			(end -0.120396 0.2794)
			(stroke
				(width 0.1)
				(type default)
			)
			(layer "B.Fab")
		)
		(fp_line
			(start 0.12065 0.3048)
			(end 0.67945 0.3048)
			(stroke
				(width 0.1)
				(type default)
			)
			(layer "B.Fab")
		)
		(fp_line
			(start 0.67945 0.3048)
			(end 0.67945 -0.305054)
			(stroke
				(width 0.1)
				(type default)
			)
			(layer "B.Fab")
		)
		(fp_line
			(start -0.120396 0.2794)
			(end 0.12065 0.2794)
			(stroke
				(width 0.1)
				(type default)
			)
			(layer "B.Fab")
		)
		(fp_line
			(start 0.12065 0.2794)
			(end 0.12065 0.3048)
			(stroke
				(width 0.1)
				(type default)
			)
			(layer "B.Fab")
		)
		(fp_line
			(start -0.12065 -0.2794)
			(end -0.12065 -0.3048)
			(stroke
				(width 0.1)
				(type default)
			)
			(layer "B.Fab")
		)
		(fp_line
			(start 0.12065 -0.2794)
			(end -0.12065 -0.2794)
			(stroke
				(width 0.1)
				(type default)
			)
			(layer "B.Fab")
		)
		(fp_line
			(start -0.67945 -0.3048)
			(end -0.67945 0.3048)
			(stroke
				(width 0.1)
				(type default)
			)
			(layer "B.Fab")
		)
		(fp_line
			(start -0.12065 -0.3048)
			(end -0.67945 -0.3048)
			(stroke
				(width 0.1)
				(type default)
			)
			(layer "B.Fab")
		)
		(fp_line
			(start 0.12065 -0.305054)
			(end 0.12065 -0.2794)
			(stroke
				(width 0.1)
				(type default)
			)
			(layer "B.Fab")
		)
		(fp_line
			(start 0.67945 -0.305054)
			(end 0.12065 -0.305054)
			(stroke
				(width 0.1)
				(type default)
			)
			(layer "B.Fab")
		)
		(pad "1" smd circle
			(at 0.40005 0 90)
			(size 0 0)
			(layers "B.Cu" "B.Mask" "B.Paste")
			(net "SMB_HOST_CLK_3V3AUX_SDA")
		)
		(pad "2" smd circle
			(at -0.40005 0 90)
			(size 0 0)
			(layers "B.Cu" "B.Mask" "B.Paste")
			(net "P3V3_AUX")
		)
	)
)
